#ISCELL
  pure_quanta quanta_title_block_c *
  *
#ISCELL
  standard offpage *
  page368_i1
#CELL
  pure_quanta mosfet_nch_dual *
  page368_i10
#CELL
  pure_quanta q_res *
  page368_i11
#ISCELL
  pure_quanta_power universal_power *
  page368_i12
#CELL
  pure_quanta q_res *
  page368_i13
#ISCELL
  standard offpage *
  page368_i14
#ISCELL
  standard offpage *
  page368_i15
#ISCELL
  standard offpage *
  page368_i16
#ISCELL
  standard offpage *
  page368_i2
#CELL
  pure_quanta mosfet_nch_dual *
  page368_i3
#ISCELL
  pure_quanta_power universal_gnd *
  page368_i4
#CELL
  pure_quanta q_res *
  page368_i5
#ISCELL
  pure_quanta_power universal_power *
  page368_i6
#CELL
  pure_quanta q_res *
  page368_i7
#CELL
  pure_quanta q_res *
  page368_i8
#ISCELL
  pure_quanta_power universal_gnd *
  page368_i9
